#ISCELL
  mstr_misc dns *
  *
#ISCELL
  pure_quanta quanta_title_block_c *
  *
#ISCELL
  standard offpage *
  page132_i1
#CELL
  pure_quanta q_res *
  page132_i100
#ISCELL
  standard offpage *
  page132_i101
#ISCELL
  standard offpage *
  page132_i102
#CELL
  pure_quanta q_res *
  page132_i103
#CELL
  pure_quanta q_res *
  page132_i104
#CELL
  pure_quanta q_res *
  page132_i105
#ISCELL
  logical_power universal_power *
  page132_i106
#CELL
  pure_quanta q_res *
  page132_i107
#CELL
  pure_quanta 74lvc1g08w57 *
  page132_i108
#ISCELL
  logical_power universal_gnd *
  page132_i109
#CELL
  pure_quanta q_cap *
  page132_i110
#CELL
  pure_quanta q_res *
  page132_i111
#CELL
  pure_quanta q_res *
  page132_i112
#ISCELL
  logical_power universal_power *
  page132_i113
#ISCELL
  standard offpage *
  page132_i115
#ISCELL
  logical_power universal_gnd *
  page132_i116
#ISCELL
  standard offpage *
  page132_i117
#ISCELL
  logical_power universal_power *
  page132_i118
#CELL
  pure_quanta q_res *
  page132_i119
#ISCELL
  logical_power universal_gnd *
  page132_i14
#CELL
  pure_quanta q_cap *
  page132_i15
#ISCELL
  logical_power universal_power *
  page132_i16
#ISCELL
  standard offpage *
  page132_i17
#ISCELL
  standard offpage *
  page132_i18
#ISCELL
  standard offpage *
  page132_i2
#CELL
  pure_quanta q_res *
  page132_i23
#ISCELL
  logical_power universal_gnd *
  page132_i24
#CELL
  pure_quanta q_res *
  page132_i25
#ISCELL
  logical_power universal_gnd *
  page132_i26
#CELL
  pure_quanta q_res *
  page132_i27
#ISCELL
  logical_power universal_gnd *
  page132_i28
#CELL
  pure_quanta q_res *
  page132_i29
#CELL
  pure_quanta mosfet_n *
  page132_i3
#ISCELL
  logical_power universal_power *
  page132_i30
#CELL
  pure_quanta q_res *
  page132_i31
#CELL
  pure_quanta q_res *
  page132_i32
#CELL
  pure_quanta q_res *
  page132_i33
#CELL
  pure_quanta q_res *
  page132_i34
#ISCELL
  standard offpage *
  page132_i37
#ISCELL
  logical_power universal_gnd *
  page132_i38
#CELL
  pure_quanta q_cap *
  page132_i39
#ISCELL
  logical_power universal_gnd *
  page132_i4
#ISCELL
  logical_power universal_power *
  page132_i40
#ISCELL
  logical_power universal_gnd *
  page132_i41
#ISCELL
  standard offpage *
  page132_i42
#ISCELL
  standard offpage *
  page132_i43
#ISCELL
  standard offpage *
  page132_i44
#ISCELL
  standard offpage *
  page132_i45
#ISCELL
  standard offpage *
  page132_i46
#ISCELL
  standard offpage *
  page132_i47
#ISCELL
  logical_power universal_gnd *
  page132_i5
#ISCELL
  standard offpage *
  page132_i50
#ISCELL
  logical_power universal_gnd *
  page132_i55
#CELL
  pure_quanta 74lvc1g08w57 *
  page132_i56
#ISCELL
  logical_power universal_gnd *
  page132_i57
#CELL
  pure_quanta q_cap *
  page132_i58
#ISCELL
  logical_power universal_power *
  page132_i59
#ISCELL
  standard offpage *
  page132_i6
#ISCELL
  standard offpage *
  page132_i60
#ISCELL
  standard offpage *
  page132_i63
#ISCELL
  standard offpage *
  page132_i64
#CELL
  pure_quanta q_res *
  page132_i65
#CELL
  pure_quanta pca9555apw *
  page132_i66
#ISCELL
  standard offpage *
  page132_i67
#ISCELL
  standard offpage *
  page132_i68
#CELL
  pure_quanta q_res *
  page132_i7
#ISCELL
  logical_power universal_power *
  page132_i8
#ISCELL
  logical_power universal_gnd *
  page132_i81
#ISCELL
  logical_power universal_gnd *
  page132_i84
#CELL
  pure_quanta apx80929sag7 *
  page132_i85
#ISCELL
  logical_power universal_power *
  page132_i86
#CELL
  pure_quanta q_cap *
  page132_i87
#ISCELL
  standard offpage *
  page132_i88
#ISCELL
  logical_power universal_power *
  page132_i89
#CELL
  pure_quanta 74lvc1g08w57 *
  page132_i9
#CELL
  pure_quanta q_cap *
  page132_i90
#ISCELL
  logical_power universal_gnd *
  page132_i91
#CELL
  pure_quanta 74lvc1g08w57 *
  page132_i92
#ISCELL
  logical_power universal_gnd *
  page132_i93
#ISCELL
  logical_power universal_power *
  page132_i94
#CELL
  pure_quanta q_res *
  page132_i95
#CELL
  pure_quanta q_res *
  page132_i96
#ISCELL
  standard offpage *
  page132_i98
#CELL
  pure_quanta q_res *
  page132_i99
